(kicad_pcb
	(version 20260206)
	(generator "pcbnew")
	(generator_version "10.0")
	(general
		(thickness 1.6)
		(legacy_teardrops no)
	)
	(paper "A4")
	(title_block
		(title "03242023_DA0F0TMBIJ0_F0T_Motherboard_J_brd_V01_OCP.brd")
		(comment 1 "Grand Teton / footprints 2237-2241 of 6105")
	)
	(layers
		(0 "F.Cu" signal "TOP")
		(4 "In1.Cu" signal "GND")
		(6 "In2.Cu" signal "IN1")
		(8 "In3.Cu" signal "GND1")
		(10 "In4.Cu" signal "IN2")
		(12 "In5.Cu" signal "GND2")
		(14 "In6.Cu" signal "IN3")
		(16 "In7.Cu" signal "GND3")
		(18 "In8.Cu" signal "VCC")
		(20 "In9.Cu" signal "VCC1")
		(22 "In10.Cu" signal "GND4")
		(24 "In11.Cu" signal "IN4")
		(26 "In12.Cu" signal "GND5")
		(28 "In13.Cu" signal "IN5")
		(30 "In14.Cu" signal "GND6")
		(32 "In15.Cu" signal "IN6")
		(34 "In16.Cu" signal "GND7")
		(2 "B.Cu" signal "BOTTOM")
		(9 "F.Adhes" user "F.Adhesive")
		(11 "B.Adhes" user "B.Adhesive")
		(13 "F.Paste" user "Package Geometry/Pastemask Top")
		(15 "B.Paste" user "Package Geometry/Pastemask Bottom")
		(5 "F.SilkS" user "Ref Des/Silkscreen Top")
		(7 "B.SilkS" user "Ref Des/Silkscreen Bottom")
		(1 "F.Mask" user "Board Geometry/Soldermask Top")
		(3 "B.Mask" user "Board Geometry/Soldermask Bottom")
		(17 "Dwgs.User" user "User.Drawings")
		(19 "Cmts.User" user "User.Comments")
		(21 "Eco1.User" user "User.Eco1")
		(23 "Eco2.User" user "User.Eco2")
		(25 "Edge.Cuts" user "Board Geometry/Outline")
		(27 "Margin" user)
		(31 "F.CrtYd" user "Package Geometry/Place Bound Top")
		(29 "B.CrtYd" user "Package Geometry/Place Bound Bottom")
		(35 "F.Fab" user "Ref Des/Assembly Top")
		(33 "B.Fab" user "Ref Des/Assembly Bottom")
	)
	(footprint ""
		(layer "F.Cu")
		(at 441.36564 -100.27158 90)
		(property "Reference" "R4747"
			(at 0 0 90)
			(layer "F.SilkS")
			(hide yes)
			(effects
				(font
					(size 1.27 1.27)
				)
			)
		)
		(property "Value" ""
			(at 0 0 90)
			(layer "F.Fab")
			(effects
				(font
					(size 1.27 1.27)
				)
			)
		)
		(duplicate_pad_numbers_are_jumpers no)
		(fp_line
			(start 0.7874 -0.4064)
			(end 0.7874 0.4064)
			(stroke
				(width 0.1524)
				(type default)
			)
			(layer "F.SilkS")
		)
		(fp_line
			(start -0.7874 -0.4064)
			(end 0.7874 -0.4064)
			(stroke
				(width 0.1524)
				(type default)
			)
			(layer "F.SilkS")
		)
		(fp_line
			(start 0.7874 0.4064)
			(end -0.7874 0.4064)
			(stroke
				(width 0.1524)
				(type default)
			)
			(layer "F.SilkS")
		)
		(fp_line
			(start -0.7874 0.4064)
			(end -0.7874 -0.4064)
			(stroke
				(width 0.1524)
				(type default)
			)
			(layer "F.SilkS")
		)
		(fp_line
			(start -0.12065 -0.305054)
			(end -0.12065 -0.2794)
			(stroke
				(width 0.1)
				(type default)
			)
			(layer "F.Fab")
		)
		(fp_line
			(start -0.67945 -0.305054)
			(end -0.12065 -0.305054)
			(stroke
				(width 0.1)
				(type default)
			)
			(layer "F.Fab")
		)
		(fp_line
			(start 0.67945 -0.3048)
			(end 0.67945 0.3048)
			(stroke
				(width 0.1)
				(type default)
			)
			(layer "F.Fab")
		)
		(fp_line
			(start 0.12065 -0.3048)
			(end 0.67945 -0.3048)
			(stroke
				(width 0.1)
				(type default)
			)
			(layer "F.Fab")
		)
		(fp_line
			(start 0.12065 -0.2794)
			(end 0.12065 -0.3048)
			(stroke
				(width 0.1)
				(type default)
			)
			(layer "F.Fab")
		)
		(fp_line
			(start -0.12065 -0.2794)
			(end 0.12065 -0.2794)
			(stroke
				(width 0.1)
				(type default)
			)
			(layer "F.Fab")
		)
		(fp_line
			(start 0.120396 0.2794)
			(end -0.12065 0.2794)
			(stroke
				(width 0.1)
				(type default)
			)
			(layer "F.Fab")
		)
		(fp_line
			(start -0.12065 0.2794)
			(end -0.12065 0.3048)
			(stroke
				(width 0.1)
				(type default)
			)
			(layer "F.Fab")
		)
		(fp_line
			(start 0.67945 0.3048)
			(end 0.120396 0.3048)
			(stroke
				(width 0.1)
				(type default)
			)
			(layer "F.Fab")
		)
		(fp_line
			(start 0.120396 0.3048)
			(end 0.120396 0.2794)
			(stroke
				(width 0.1)
				(type default)
			)
			(layer "F.Fab")
		)
		(fp_line
			(start -0.12065 0.3048)
			(end -0.67945 0.3048)
			(stroke
				(width 0.1)
				(type default)
			)
			(layer "F.Fab")
		)
		(fp_line
			(start -0.67945 0.3048)
			(end -0.67945 -0.305054)
			(stroke
				(width 0.1)
				(type default)
			)
			(layer "F.Fab")
		)
		(pad "1" smd circle
			(at -0.40005 0 90)
			(size 0 0)
			(layers "F.Cu" "F.Mask" "F.Paste")
			(net "OCP_SFF_AUX_PWR_PLD_EN")
		)
		(pad "2" smd circle
			(at 0.40005 0 90)
			(size 0 0)
			(layers "F.Cu" "F.Mask" "F.Paste")
			(net "OCP_SFF_AUX_PWR_PLD_EN_R")
		)
	)
	(footprint ""
		(layer "F.Cu")
		(at 436.608474 -103.768398 90)
		(property "Reference" "PR4525"
			(at 0 0 90)
			(layer "F.SilkS")
			(hide yes)
			(effects
				(font
					(size 1.27 1.27)
				)
			)
		)
		(property "Value" ""
			(at 0 0 90)
			(layer "F.Fab")
			(effects
				(font
					(size 1.27 1.27)
				)
			)
		)
		(duplicate_pad_numbers_are_jumpers no)
		(fp_line
			(start 0.7874 -0.4064)
			(end 0.7874 0.4064)
			(stroke
				(width 0.1524)
				(type default)
			)
			(layer "F.SilkS")
		)
		(fp_line
			(start -0.7874 -0.4064)
			(end 0.7874 -0.4064)
			(stroke
				(width 0.1524)
				(type default)
			)
			(layer "F.SilkS")
		)
		(fp_line
			(start 0.7874 0.4064)
			(end -0.7874 0.4064)
			(stroke
				(width 0.1524)
				(type default)
			)
			(layer "F.SilkS")
		)
		(fp_line
			(start -0.7874 0.4064)
			(end -0.7874 -0.4064)
			(stroke
				(width 0.1524)
				(type default)
			)
			(layer "F.SilkS")
		)
		(fp_line
			(start -0.12065 -0.305054)
			(end -0.12065 -0.2794)
			(stroke
				(width 0.1)
				(type default)
			)
			(layer "F.Fab")
		)
		(fp_line
			(start -0.67945 -0.305054)
			(end -0.12065 -0.305054)
			(stroke
				(width 0.1)
				(type default)
			)
			(layer "F.Fab")
		)
		(fp_line
			(start 0.67945 -0.3048)
			(end 0.67945 0.3048)
			(stroke
				(width 0.1)
				(type default)
			)
			(layer "F.Fab")
		)
		(fp_line
			(start 0.12065 -0.3048)
			(end 0.67945 -0.3048)
			(stroke
				(width 0.1)
				(type default)
			)
			(layer "F.Fab")
		)
		(fp_line
			(start 0.12065 -0.2794)
			(end 0.12065 -0.3048)
			(stroke
				(width 0.1)
				(type default)
			)
			(layer "F.Fab")
		)
		(fp_line
			(start -0.12065 -0.2794)
			(end 0.12065 -0.2794)
			(stroke
				(width 0.1)
				(type default)
			)
			(layer "F.Fab")
		)
		(fp_line
			(start 0.120396 0.2794)
			(end -0.12065 0.2794)
			(stroke
				(width 0.1)
				(type default)
			)
			(layer "F.Fab")
		)
		(fp_line
			(start -0.12065 0.2794)
			(end -0.12065 0.3048)
			(stroke
				(width 0.1)
				(type default)
			)
			(layer "F.Fab")
		)
		(fp_line
			(start 0.67945 0.3048)
			(end 0.120396 0.3048)
			(stroke
				(width 0.1)
				(type default)
			)
			(layer "F.Fab")
		)
		(fp_line
			(start 0.120396 0.3048)
			(end 0.120396 0.2794)
			(stroke
				(width 0.1)
				(type default)
			)
			(layer "F.Fab")
		)
		(fp_line
			(start -0.12065 0.3048)
			(end -0.67945 0.3048)
			(stroke
				(width 0.1)
				(type default)
			)
			(layer "F.Fab")
		)
		(fp_line
			(start -0.67945 0.3048)
			(end -0.67945 -0.305054)
			(stroke
				(width 0.1)
				(type default)
			)
			(layer "F.Fab")
		)
		(pad "1" smd circle
			(at -0.40005 0 90)
			(size 0 0)
			(layers "F.Cu" "F.Mask" "F.Paste")
			(net "P3V3_OCP_SFF_R")
		)
		(pad "2" smd circle
			(at 0.40005 0 90)
			(size 0 0)
			(layers "F.Cu" "F.Mask" "F.Paste")
			(net "P3V3_OCP_GATE_PU202_1")
		)
	)
	(footprint ""
		(layer "F.Cu")
		(at 174.613062 -32.935672 90)
		(property "Reference" "PC2235"
			(at 0 0 90)
			(layer "F.SilkS")
			(hide yes)
			(effects
				(font
					(size 1.27 1.27)
				)
			)
		)
		(property "Value" ""
			(at 0 0 90)
			(layer "F.Fab")
			(effects
				(font
					(size 1.27 1.27)
				)
			)
		)
		(duplicate_pad_numbers_are_jumpers no)
		(fp_line
			(start 0.7874 -0.4064)
			(end 0.7874 0.4064)
			(stroke
				(width 0.1524)
				(type default)
			)
			(layer "F.SilkS")
		)
		(fp_line
			(start -0.7874 -0.4064)
			(end 0.7874 -0.4064)
			(stroke
				(width 0.1524)
				(type default)
			)
			(layer "F.SilkS")
		)
		(fp_line
			(start 0.7874 0.4064)
			(end -0.7874 0.4064)
			(stroke
				(width 0.1524)
				(type default)
			)
			(layer "F.SilkS")
		)
		(fp_line
			(start -0.7874 0.4064)
			(end -0.7874 -0.4064)
			(stroke
				(width 0.1524)
				(type default)
			)
			(layer "F.SilkS")
		)
		(fp_line
			(start -0.12065 -0.305054)
			(end -0.12065 -0.2794)
			(stroke
				(width 0.1)
				(type default)
			)
			(layer "F.Fab")
		)
		(fp_line
			(start -0.67945 -0.305054)
			(end -0.12065 -0.305054)
			(stroke
				(width 0.1)
				(type default)
			)
			(layer "F.Fab")
		)
		(fp_line
			(start 0.67945 -0.3048)
			(end 0.67945 0.3048)
			(stroke
				(width 0.1)
				(type default)
			)
			(layer "F.Fab")
		)
		(fp_line
			(start 0.12065 -0.3048)
			(end 0.67945 -0.3048)
			(stroke
				(width 0.1)
				(type default)
			)
			(layer "F.Fab")
		)
		(fp_line
			(start 0.12065 -0.2794)
			(end 0.12065 -0.3048)
			(stroke
				(width 0.1)
				(type default)
			)
			(layer "F.Fab")
		)
		(fp_line
			(start -0.12065 -0.2794)
			(end 0.12065 -0.2794)
			(stroke
				(width 0.1)
				(type default)
			)
			(layer "F.Fab")
		)
		(fp_line
			(start 0.120396 0.2794)
			(end -0.12065 0.2794)
			(stroke
				(width 0.1)
				(type default)
			)
			(layer "F.Fab")
		)
		(fp_line
			(start -0.12065 0.2794)
			(end -0.12065 0.3048)
			(stroke
				(width 0.1)
				(type default)
			)
			(layer "F.Fab")
		)
		(fp_line
			(start 0.67945 0.3048)
			(end 0.120396 0.3048)
			(stroke
				(width 0.1)
				(type default)
			)
			(layer "F.Fab")
		)
		(fp_line
			(start 0.120396 0.3048)
			(end 0.120396 0.2794)
			(stroke
				(width 0.1)
				(type default)
			)
			(layer "F.Fab")
		)
		(fp_line
			(start -0.12065 0.3048)
			(end -0.67945 0.3048)
			(stroke
				(width 0.1)
				(type default)
			)
			(layer "F.Fab")
		)
		(fp_line
			(start -0.67945 0.3048)
			(end -0.67945 -0.305054)
			(stroke
				(width 0.1)
				(type default)
			)
			(layer "F.Fab")
		)
		(pad "1" smd circle
			(at -0.40005 0 90)
			(size 0 0)
			(layers "F.Cu" "F.Mask" "F.Paste")
			(net "P12V_SCM_IMON")
		)
		(pad "2" smd circle
			(at 0.40005 0 90)
			(size 0 0)
			(layers "F.Cu" "F.Mask" "F.Paste")
			(net "GND")
		)
	)
	(footprint ""
		(layer "F.Cu")
		(at 132.08 -70.749922 -90)
		(property "Reference" "J43"
			(at -1.860296 7.31012 0)
			(unlocked yes)
			(layer "F.SilkS")
			(effects
				(font
					(size 0.7874 0.5842)
					(thickness 0.1524)
				)
				(justify left)
			)
		)
		(property "Value" ""
			(at 0 0 270)
			(layer "F.Fab")
			(effects
				(font
					(size 1.27 1.27)
				)
			)
		)
		(duplicate_pad_numbers_are_jumpers no)
		(fp_line
			(start -1.249934 19.100038)
			(end -1.249934 -1.320038)
			(stroke
				(width 0.1524)
				(type default)
			)
			(layer "F.SilkS")
		)
		(fp_line
			(start 1.249934 19.100038)
			(end -1.249934 19.100038)
			(stroke
				(width 0.1524)
				(type default)
			)
			(layer "F.SilkS")
		)
		(fp_line
			(start -1.249934 -1.320038)
			(end 1.249934 -1.320038)
			(stroke
				(width 0.1524)
				(type default)
			)
			(layer "F.SilkS")
		)
		(fp_line
			(start 1.249934 -1.320038)
			(end 1.249934 19.100038)
			(stroke
				(width 0.1524)
				(type default)
			)
			(layer "F.SilkS")
		)
		(fp_poly
			(pts
				(xy 2.807208 0.48641) (xy 1.529842 -0.1524) (xy 2.807208 -0.79121)
			)
			(stroke
				(width 0)
				(type default)
			)
			(fill yes)
			(layer "F.SilkS")
		)
		(fp_line
			(start -1.249934 19.100038)
			(end -1.249934 -1.320038)
			(stroke
				(width 0.1)
				(type default)
			)
			(layer "F.Fab")
		)
		(fp_line
			(start 1.249934 19.100038)
			(end -1.249934 19.100038)
			(stroke
				(width 0.1)
				(type default)
			)
			(layer "F.Fab")
		)
		(fp_line
			(start -1.249934 -1.320038)
			(end 1.249934 -1.320038)
			(stroke
				(width 0.1)
				(type default)
			)
			(layer "F.Fab")
		)
		(fp_line
			(start 1.249934 -1.320038)
			(end 1.249934 19.100038)
			(stroke
				(width 0.1)
				(type default)
			)
			(layer "F.Fab")
		)
		(fp_poly
			(pts
				(xy -2.7432 0.63881) (xy -2.7432 -0.63881) (xy -1.465834 0)
			)
			(stroke
				(width 0)
				(type default)
			)
			(fill yes)
			(layer "F.Fab")
		)
		(fp_text user "8"
			(at -1.7526 17.80667 270)
			(unlocked yes)
			(layer "F.SilkS")
			(effects
				(font
					(size 0.7874 0.5842)
					(thickness 0.1524)
				)
			)
		)
		(fp_text user "8"
			(at 1.881124 17.759934 0)
			(unlocked yes)
			(layer "B.SilkS")
			(effects
				(font
					(size 0.7874 0.5842)
					(thickness 0.1524)
				)
				(justify mirror)
			)
		)
		(fp_text user "1"
			(at 1.878584 -0.068326 0)
			(unlocked yes)
			(layer "B.SilkS")
			(effects
				(font
					(size 0.7874 0.5842)
					(thickness 0.1524)
				)
				(justify mirror)
			)
		)
		(fp_text user "8"
			(at -1.1938 17.80667 270)
			(unlocked yes)
			(layer "B.Fab")
			(effects
				(font
					(size 0.7874 0.5842)
					(thickness 0.1524)
				)
				(justify mirror)
			)
		)
		(fp_text user "1"
			(at -1.1176 -0.02413 270)
			(unlocked yes)
			(layer "B.Fab")
			(effects
				(font
					(size 0.7874 0.5842)
					(thickness 0.1524)
				)
				(justify mirror)
			)
		)
		(fp_text user "8"
			(at -1.7526 17.80667 270)
			(unlocked yes)
			(layer "F.Fab")
			(effects
				(font
					(size 0.7874 0.5842)
					(thickness 0.1524)
				)
			)
		)
		(pad "1" thru_hole rect
			(at 0 0 270)
			(size 1.5494 1.5494)
			(drill 1.0414)
			(layers "*.Cu" "*.Mask")
			(remove_unused_layers no)
			(net "P3V3_AUX_BMC_D")
			(clearance 0)
			(padstack
				(mode front_inner_back)
				(layer "Inner"
					(shape circle)
					(size 1.5494 1.5494)
					(clearance 0)
				)
				(layer "B.Cu"
					(shape rect)
					(size 1.5494 1.5494)
					(clearance 0)
				)
			)
		)
		(pad "2" thru_hole circle
			(at 0 2.54 270)
			(size 1.5494 1.5494)
			(drill 1.0414)
			(layers "*.Cu" "*.Mask")
			(remove_unused_layers no)
			(net "JTAG_BMC_PLD_TDO")
			(clearance 0)
		)
		(pad "3" thru_hole circle
			(at 0 5.08 270)
			(size 1.5494 1.5494)
			(drill 1.0414)
			(layers "*.Cu" "*.Mask")
			(remove_unused_layers no)
			(net "JTAG_BMC_PLD_TDI")
			(clearance 0)
		)
		(pad "4" thru_hole circle
			(at 0 7.62 270)
			(size 1.5494 1.5494)
			(drill 1.0414)
			(layers "*.Cu" "*.Mask")
			(remove_unused_layers no)
			(net "TP_PLD_CONN_P4")
			(clearance 0)
		)
		(pad "5" thru_hole circle
			(at 0 10.16 270)
			(size 1.5494 1.5494)
			(drill 1.0414)
			(layers "*.Cu" "*.Mask")
			(remove_unused_layers no)
			(net "TP_PLD_CONN_P5")
			(clearance 0)
		)
		(pad "6" thru_hole circle
			(at 0 12.7 270)
			(size 1.5494 1.5494)
			(drill 1.0414)
			(layers "*.Cu" "*.Mask")
			(remove_unused_layers no)
			(net "JTAG_BMC_PLD_TMS")
			(clearance 0)
		)
		(pad "7" thru_hole circle
			(at 0 15.24 270)
			(size 1.5494 1.5494)
			(drill 1.0414)
			(layers "*.Cu" "*.Mask")
			(remove_unused_layers no)
			(net "GND")
			(clearance 0)
		)
		(pad "8" thru_hole circle
			(at 0 17.78 270)
			(size 1.5494 1.5494)
			(drill 1.0414)
			(layers "*.Cu" "*.Mask")
			(remove_unused_layers no)
			(net "JTAG_BMC_PLD_TCK")
			(clearance 0)
		)
	)
	(footprint ""
		(layer "F.Cu")
		(at 225.933 -227.929948 90)
		(property "Reference" "U31"
			(at 0.22733 -5.08 0)
			(unlocked yes)
			(layer "F.SilkS")
			(effects
				(font
					(size 0.7874 0.5842)
					(thickness 0.1524)
				)
				(justify left)
			)
		)
		(property "Value" ""
			(at 0 0 90)
			(layer "F.Fab")
			(effects
				(font
					(size 1.27 1.27)
				)
			)
		)
		(duplicate_pad_numbers_are_jumpers no)
		(fp_line
			(start 1.4224 -2.5146)
			(end 0.4572 -2.5146)
			(stroke
				(width 0.1524)
				(type default)
			)
			(layer "F.SilkS")
		)
		(fp_line
			(start 0.4572 -2.5146)
			(end 0 -2.0574)
			(stroke
				(width 0.1524)
				(type default)
			)
			(layer "F.SilkS")
		)
		(fp_line
			(start -0.4572 -2.5146)
			(end -1.4224 -2.5146)
			(stroke
				(width 0.1524)
				(type default)
			)
			(layer "F.SilkS")
		)
		(fp_line
			(start -1.4224 -2.5146)
			(end -1.4224 2.5146)
			(stroke
				(width 0.1524)
				(type default)
			)
			(layer "F.SilkS")
		)
		(fp_line
			(start 0 -2.0574)
			(end -0.4572 -2.5146)
			(stroke
				(width 0.1524)
				(type default)
			)
			(layer "F.SilkS")
		)
		(fp_line
			(start 1.4224 2.5146)
			(end 1.4224 -2.5146)
			(stroke
				(width 0.1524)
				(type default)
			)
			(layer "F.SilkS")
		)
		(fp_line
			(start -1.4224 2.5146)
			(end 1.4224 2.5146)
			(stroke
				(width 0.1524)
				(type default)
			)
			(layer "F.SilkS")
		)
		(fp_poly
			(pts
				(xy -3.069844 -3.694938) (xy -2.307844 -3.694938) (xy -2.688844 -2.932938)
			)
			(stroke
				(width 0)
				(type default)
			)
			(fill yes)
			(layer "F.SilkS")
		)
		(fp_line
			(start 2.0066 -2.5146)
			(end -2.0066 -2.5146)
			(stroke
				(width 0.1)
				(type default)
			)
			(layer "F.Fab")
		)
		(fp_line
			(start -2.0066 -2.5146)
			(end -2.0066 -2.114804)
			(stroke
				(width 0.1)
				(type default)
			)
			(layer "F.Fab")
		)
		(fp_line
			(start -2.0066 -2.114804)
			(end -2.648712 -2.114804)
			(stroke
				(width 0.1)
				(type default)
			)
			(layer "F.Fab")
		)
		(fp_line
			(start -2.648712 -2.114804)
			(end -2.648712 2.112264)
			(stroke
				(width 0.1)
				(type default)
			)
			(layer "F.Fab")
		)
		(fp_line
			(start 2.642616 -2.112264)
			(end 2.0066 -2.112264)
			(stroke
				(width 0.1)
				(type default)
			)
			(layer "F.Fab")
		)
		(fp_line
			(start 2.0066 -2.112264)
			(end 2.0066 -2.5146)
			(stroke
				(width 0.1)
				(type default)
			)
			(layer "F.Fab")
		)
		(fp_line
			(start 2.642616 2.112264)
			(end 2.642616 -2.112264)
			(stroke
				(width 0.1)
				(type default)
			)
			(layer "F.Fab")
		)
		(fp_line
			(start 2.0066 2.112264)
			(end 2.642616 2.112264)
			(stroke
				(width 0.1)
				(type default)
			)
			(layer "F.Fab")
		)
		(fp_line
			(start -2.0066 2.112264)
			(end -2.0066 2.5146)
			(stroke
				(width 0.1)
				(type default)
			)
			(layer "F.Fab")
		)
		(fp_line
			(start -2.648712 2.112264)
			(end -2.0066 2.112264)
			(stroke
				(width 0.1)
				(type default)
			)
			(layer "F.Fab")
		)
		(fp_line
			(start 2.0066 2.5146)
			(end 2.0066 2.112264)
			(stroke
				(width 0.1)
				(type default)
			)
			(layer "F.Fab")
		)
		(fp_line
			(start -2.0066 2.5146)
			(end 2.0066 2.5146)
			(stroke
				(width 0.1)
				(type default)
			)
			(layer "F.Fab")
		)
		(fp_poly
			(pts
				(xy -3.6322 -1.869186) (xy -4.3942 -1.488186) (xy -4.3942 -2.250186)
			)
			(stroke
				(width 0)
				(type default)
			)
			(fill yes)
			(layer "F.Fab")
		)
		(pad "1" smd rect
			(at -2.6416 -1.905)
			(size 0.5588 1.7272)
			(layers "F.Cu" "F.Mask" "F.Paste")
			(net "PVNN_TERM_CPU1")
		)
		(pad "2" smd rect
			(at -2.6416 -0.635)
			(size 0.5588 1.7272)
			(layers "F.Cu" "F.Mask" "F.Paste")
			(net "SMB_S3M_CPU1_R_SCL")
		)
		(pad "3" smd rect
			(at -2.6416 0.635)
			(size 0.5588 1.7272)
			(layers "F.Cu" "F.Mask" "F.Paste")
			(net "SMB_S3M_CPU1_R_SDA")
		)
		(pad "4" smd rect
			(at -2.6416 1.905)
			(size 0.5588 1.7272)
			(layers "F.Cu" "F.Mask" "F.Paste")
			(net "GND")
		)
		(pad "5" smd rect
			(at 2.6416 1.905)
			(size 0.5588 1.7272)
			(layers "F.Cu" "F.Mask" "F.Paste")
			(net "TP_SMB_S3M_CPU1_EN")
		)
		(pad "6" smd rect
			(at 2.6416 0.635)
			(size 0.5588 1.7272)
			(layers "F.Cu" "F.Mask" "F.Paste")
			(net "SMB_S3M_CPU1_3V3AUX_SDA")
		)
		(pad "7" smd rect
			(at 2.6416 -0.635)
			(size 0.5588 1.7272)
			(layers "F.Cu" "F.Mask" "F.Paste")
			(net "SMB_S3M_CPU1_3V3AUX_SCL")
		)
		(pad "8" smd rect
			(at 2.6416 -1.905)
			(size 0.5588 1.7272)
			(layers "F.Cu" "F.Mask" "F.Paste")
			(net "P3V3_AUX")
		)
	)
)
